# T6G (Grand Teton) — schematic netlist excerpt (pin names and nets, part order shuffled) for the footprints in the layout excerpt that follows; sources: Cadence DE-HDL packaged netlist, KiCad conversion of 04192023_DAF0TMB3IC0_F0TG_MB_C_brd_V02_OCP.brd

R471  Q_RES  33 5% CHIP  pkg 0402LF  page 29 : A = ESPI_CPU0_D3 ; B = ESPI_CPU0_R_D3
C100  Q_CAP  0.1UF 25V 10% X7R  pkg 0402  page 89 : A = P3V3_AUX ; B = GND
R807  Q_RES  0 5% CHIP  pkg 0201LF  page 185 : A = SMB_RT_CPU1_P3_ROM_MUX_2D_SCL ; B = SMB_RT_CPU1_P3_ROM_MUX_2D_R_SCL

(kicad_pcb
	(version 20260206)
	(generator "pcbnew")
	(generator_version "10.0")
	(general
		(thickness 1.6)
		(legacy_teardrops no)
	)
	(paper "A4")
	(title_block
		(title "04192023_DAF0TMB3IC0_F0TG_MB_C_brd_V02_OCP.brd")
		(comment 1 "Grand Teton / footprints 7579-7581 of 8354")
	)
	(layers
		(0 "F.Cu" signal "TOP")
		(4 "In1.Cu" signal "GND")
		(6 "In2.Cu" signal "IN1")
		(8 "In3.Cu" signal "GND1")
		(10 "In4.Cu" signal "IN2")
		(12 "In5.Cu" signal "GND2")
		(14 "In6.Cu" signal "IN3")
		(16 "In7.Cu" signal "GND3")
		(18 "In8.Cu" signal "VCC")
		(20 "In9.Cu" signal "VCC1")
		(22 "In10.Cu" signal "GND4")
		(24 "In11.Cu" signal "IN4")
		(26 "In12.Cu" signal "GND5")
		(28 "In13.Cu" signal "IN5")
		(30 "In14.Cu" signal "GND6")
		(32 "In15.Cu" signal "IN6")
		(34 "In16.Cu" signal "GND7")
		(2 "B.Cu" signal "BOTTOM")
		(9 "F.Adhes" user "F.Adhesive")
		(11 "B.Adhes" user "B.Adhesive")
		(13 "F.Paste" user "Package Geometry/Pastemask Top")
		(15 "B.Paste" user "Package Geometry/Pastemask Bottom")
		(5 "F.SilkS" user "Ref Des/Silkscreen Top")
		(7 "B.SilkS" user "Ref Des/Silkscreen Bottom")
		(1 "F.Mask" user "Board Geometry/Soldermask Top")
		(3 "B.Mask" user "Board Geometry/Soldermask Bottom")
		(17 "Dwgs.User" user "User.Drawings")
		(19 "Cmts.User" user "User.Comments")
		(21 "Eco1.User" user "User.Eco1")
		(23 "Eco2.User" user "User.Eco2")
		(25 "Edge.Cuts" user "Board Geometry/Outline")
		(27 "Margin" user)
		(31 "F.CrtYd" user "Package Geometry/Place Bound Top")
		(29 "B.CrtYd" user "Package Geometry/Place Bound Bottom")
		(35 "F.Fab" user "Ref Des/Assembly Top")
		(33 "B.Fab" user "Ref Des/Assembly Bottom")
	)
	(footprint ""
		(layer "B.Cu")
		(at 393.617958 -325.878952)
		(property "Reference" "R471"
			(at 0 0 0)
			(layer "B.SilkS")
			(hide yes)
			(effects
				(font
					(size 1.27 1.27)
				)
				(justify mirror)
			)
		)
		(property "Value" ""
			(at 0 0 0)
			(layer "B.Fab")
			(effects
				(font
					(size 1.27 1.27)
				)
				(justify mirror)
			)
		)
		(duplicate_pad_numbers_are_jumpers no)
		(fp_line
			(start -0.7874 -0.4064)
			(end -0.7874 0.4064)
			(stroke
				(width 0.1524)
				(type default)
			)
			(layer "B.SilkS")
		)
		(fp_line
			(start -0.7874 0.4064)
			(end 0.7874 0.4064)
			(stroke
				(width 0.1524)
				(type default)
			)
			(layer "B.SilkS")
		)
		(fp_line
			(start 0.7874 -0.4064)
			(end -0.7874 -0.4064)
			(stroke
				(width 0.1524)
				(type default)
			)
			(layer "B.SilkS")
		)
		(fp_line
			(start 0.7874 0.4064)
			(end 0.7874 -0.4064)
			(stroke
				(width 0.1524)
				(type default)
			)
			(layer "B.SilkS")
		)
		(fp_line
			(start -0.67945 -0.3048)
			(end -0.67945 0.3048)
			(stroke
				(width 0.1)
				(type default)
			)
			(layer "B.Fab")
		)
		(fp_line
			(start -0.67945 0.3048)
			(end -0.120396 0.3048)
			(stroke
				(width 0.1)
				(type default)
			)
			(layer "B.Fab")
		)
		(fp_line
			(start -0.12065 -0.3048)
			(end -0.67945 -0.3048)
			(stroke
				(width 0.1)
				(type default)
			)
			(layer "B.Fab")
		)
		(fp_line
			(start -0.12065 -0.2794)
			(end -0.12065 -0.3048)
			(stroke
				(width 0.1)
				(type default)
			)
			(layer "B.Fab")
		)
		(fp_line
			(start -0.120396 0.2794)
			(end 0.12065 0.2794)
			(stroke
				(width 0.1)
				(type default)
			)
			(layer "B.Fab")
		)
		(fp_line
			(start -0.120396 0.3048)
			(end -0.120396 0.2794)
			(stroke
				(width 0.1)
				(type default)
			)
			(layer "B.Fab")
		)
		(fp_line
			(start 0.12065 -0.305054)
			(end 0.12065 -0.2794)
			(stroke
				(width 0.1)
				(type default)
			)
			(layer "B.Fab")
		)
		(fp_line
			(start 0.12065 -0.2794)
			(end -0.12065 -0.2794)
			(stroke
				(width 0.1)
				(type default)
			)
			(layer "B.Fab")
		)
		(fp_line
			(start 0.12065 0.2794)
			(end 0.12065 0.3048)
			(stroke
				(width 0.1)
				(type default)
			)
			(layer "B.Fab")
		)
		(fp_line
			(start 0.12065 0.3048)
			(end 0.67945 0.3048)
			(stroke
				(width 0.1)
				(type default)
			)
			(layer "B.Fab")
		)
		(fp_line
			(start 0.67945 -0.305054)
			(end 0.12065 -0.305054)
			(stroke
				(width 0.1)
				(type default)
			)
			(layer "B.Fab")
		)
		(fp_line
			(start 0.67945 0.3048)
			(end 0.67945 -0.305054)
			(stroke
				(width 0.1)
				(type default)
			)
			(layer "B.Fab")
		)
		(pad "1" smd circle
			(at 0.40005 0 180)
			(size 0 0)
			(layers "B.Cu" "B.Mask" "B.Paste")
			(net "ESPI_CPU0_D3")
		)
		(pad "2" smd circle
			(at -0.40005 0 180)
			(size 0 0)
			(layers "B.Cu" "B.Mask" "B.Paste")
			(net "ESPI_CPU0_R_D3")
		)
	)
	(footprint ""
		(layer "B.Cu")
		(at 283.980636 -193.99631)
		(property "Reference" "C100"
			(at 0 0 0)
			(layer "B.SilkS")
			(hide yes)
			(effects
				(font
					(size 1.27 1.27)
				)
				(justify mirror)
			)
		)
		(property "Value" ""
			(at 0 0 0)
			(layer "B.Fab")
			(effects
				(font
					(size 1.27 1.27)
				)
				(justify mirror)
			)
		)
		(duplicate_pad_numbers_are_jumpers no)
		(fp_line
			(start -0.7874 -0.4064)
			(end -0.7874 0.4064)
			(stroke
				(width 0.1524)
				(type default)
			)
			(layer "B.SilkS")
		)
		(fp_line
			(start -0.7874 0.4064)
			(end 0.7874 0.4064)
			(stroke
				(width 0.1524)
				(type default)
			)
			(layer "B.SilkS")
		)
		(fp_line
			(start 0.7874 -0.4064)
			(end -0.7874 -0.4064)
			(stroke
				(width 0.1524)
				(type default)
			)
			(layer "B.SilkS")
		)
		(fp_line
			(start 0.7874 0.4064)
			(end 0.7874 -0.4064)
			(stroke
				(width 0.1524)
				(type default)
			)
			(layer "B.SilkS")
		)
		(fp_line
			(start -0.67945 -0.3048)
			(end -0.67945 0.3048)
			(stroke
				(width 0.1)
				(type default)
			)
			(layer "B.Fab")
		)
		(fp_line
			(start -0.67945 0.3048)
			(end -0.120396 0.3048)
			(stroke
				(width 0.1)
				(type default)
			)
			(layer "B.Fab")
		)
		(fp_line
			(start -0.12065 -0.3048)
			(end -0.67945 -0.3048)
			(stroke
				(width 0.1)
				(type default)
			)
			(layer "B.Fab")
		)
		(fp_line
			(start -0.12065 -0.2794)
			(end -0.12065 -0.3048)
			(stroke
				(width 0.1)
				(type default)
			)
			(layer "B.Fab")
		)
		(fp_line
			(start -0.120396 0.2794)
			(end 0.12065 0.2794)
			(stroke
				(width 0.1)
				(type default)
			)
			(layer "B.Fab")
		)
		(fp_line
			(start -0.120396 0.3048)
			(end -0.120396 0.2794)
			(stroke
				(width 0.1)
				(type default)
			)
			(layer "B.Fab")
		)
		(fp_line
			(start 0.12065 -0.305054)
			(end 0.12065 -0.2794)
			(stroke
				(width 0.1)
				(type default)
			)
			(layer "B.Fab")
		)
		(fp_line
			(start 0.12065 -0.2794)
			(end -0.12065 -0.2794)
			(stroke
				(width 0.1)
				(type default)
			)
			(layer "B.Fab")
		)
		(fp_line
			(start 0.12065 0.2794)
			(end 0.12065 0.3048)
			(stroke
				(width 0.1)
				(type default)
			)
			(layer "B.Fab")
		)
		(fp_line
			(start 0.12065 0.3048)
			(end 0.67945 0.3048)
			(stroke
				(width 0.1)
				(type default)
			)
			(layer "B.Fab")
		)
		(fp_line
			(start 0.67945 -0.305054)
			(end 0.12065 -0.305054)
			(stroke
				(width 0.1)
				(type default)
			)
			(layer "B.Fab")
		)
		(fp_line
			(start 0.67945 0.3048)
			(end 0.67945 -0.305054)
			(stroke
				(width 0.1)
				(type default)
			)
			(layer "B.Fab")
		)
		(pad "1" smd circle
			(at 0.40005 0 180)
			(size 0 0)
			(layers "B.Cu" "B.Mask" "B.Paste")
			(net "P3V3_AUX")
		)
		(pad "2" smd circle
			(at -0.40005 0 180)
			(size 0 0)
			(layers "B.Cu" "B.Mask" "B.Paste")
			(net "GND")
		)
	)
	(footprint ""
		(layer "B.Cu")
		(at 238.633 -339.598 180)
		(property "Reference" "R807"
			(at 0 0 0)
			(layer "B.SilkS")
			(hide yes)
			(effects
				(font
					(size 1.27 1.27)
				)
				(justify mirror)
			)
		)
		(property "Value" ""
			(at 0 0 0)
			(layer "B.Fab")
			(effects
				(font
					(size 1.27 1.27)
				)
				(justify mirror)
			)
		)
		(duplicate_pad_numbers_are_jumpers no)
		(fp_line
			(start 0.32512 0.175006)
			(end 0.32512 -0.175006)
			(stroke
				(width 0.1)
				(type default)
			)
			(layer "B.Fab")
		)
		(fp_line
			(start 0.32512 -0.175006)
			(end -0.32512 -0.175006)
			(stroke
				(width 0.1)
				(type default)
			)
			(layer "B.Fab")
		)
		(fp_line
			(start -0.32512 0.175006)
			(end 0.32512 0.175006)
			(stroke
				(width 0.1)
				(type default)
			)
			(layer "B.Fab")
		)
		(fp_line
			(start -0.32512 -0.175006)
			(end -0.32512 0.175006)
			(stroke
				(width 0.1)
				(type default)
			)
			(layer "B.Fab")
		)
		(pad "1" smd rect
			(at 0.2667 0)
			(size 0.3048 0.381)
			(layers "B.Cu" "B.Mask" "B.Paste")
			(net "SMB_RT_CPU1_P3_ROM_MUX_2D_SCL")
		)
		(pad "2" smd rect
			(at -0.2667 0 180)
			(size 0.3048 0.381)
			(layers "B.Cu" "B.Mask" "B.Paste")
			(net "SMB_RT_CPU1_P3_ROM_MUX_2D_R_SCL")
		)
	)
)
